# T6G (Grand Teton) — schematic netlist excerpt (pin names and nets, part order shuffled) for the footprints in the layout excerpt that follows; sources: Cadence DE-HDL packaged netlist, KiCad conversion of 04192023_DAF0TMB3IC0_F0TG_MB_C_brd_V02_OCP.brd

R8048  Q_RES  1K 1% EMPTY  pkg 0402LF  page 200 : A = PVDD18_S5_P0 ; B = SVID_PVDDCR_CPU1_P0_SVC_R
PC448_1  Q_CAP  22UF 16V 20% X6S  pkg C0805  page 222 : A = SW_P12V_AUX_PVDDIO_P1_FLT ; B = GND
R1262  Q_RES  10K 5% CHIP  pkg 0402LF  page 167 : A = P1V8_AUX ; B = BMC_JTAG_SEL

(kicad_pcb
	(version 20260206)
	(generator "pcbnew")
	(generator_version "10.0")
	(general
		(thickness 1.6)
		(legacy_teardrops no)
	)
	(paper "A4")
	(title_block
		(title "04192023_DAF0TMB3IC0_F0TG_MB_C_brd_V02_OCP.brd")
		(comment 1 "Grand Teton / footprints 7217-7219 of 8354")
	)
	(layers
		(0 "F.Cu" signal "TOP")
		(4 "In1.Cu" signal "GND")
		(6 "In2.Cu" signal "IN1")
		(8 "In3.Cu" signal "GND1")
		(10 "In4.Cu" signal "IN2")
		(12 "In5.Cu" signal "GND2")
		(14 "In6.Cu" signal "IN3")
		(16 "In7.Cu" signal "GND3")
		(18 "In8.Cu" signal "VCC")
		(20 "In9.Cu" signal "VCC1")
		(22 "In10.Cu" signal "GND4")
		(24 "In11.Cu" signal "IN4")
		(26 "In12.Cu" signal "GND5")
		(28 "In13.Cu" signal "IN5")
		(30 "In14.Cu" signal "GND6")
		(32 "In15.Cu" signal "IN6")
		(34 "In16.Cu" signal "GND7")
		(2 "B.Cu" signal "BOTTOM")
		(9 "F.Adhes" user "F.Adhesive")
		(11 "B.Adhes" user "B.Adhesive")
		(13 "F.Paste" user "Package Geometry/Pastemask Top")
		(15 "B.Paste" user "Package Geometry/Pastemask Bottom")
		(5 "F.SilkS" user "Ref Des/Silkscreen Top")
		(7 "B.SilkS" user "Ref Des/Silkscreen Bottom")
		(1 "F.Mask" user "Board Geometry/Soldermask Top")
		(3 "B.Mask" user "Board Geometry/Soldermask Bottom")
		(17 "Dwgs.User" user "User.Drawings")
		(19 "Cmts.User" user "User.Comments")
		(21 "Eco1.User" user "User.Eco1")
		(23 "Eco2.User" user "User.Eco2")
		(25 "Edge.Cuts" user "Board Geometry/Outline")
		(27 "Margin" user)
		(31 "F.CrtYd" user "Package Geometry/Place Bound Top")
		(29 "B.CrtYd" user "Package Geometry/Place Bound Bottom")
		(35 "F.Fab" user "Ref Des/Assembly Top")
		(33 "B.Fab" user "Ref Des/Assembly Bottom")
	)
	(footprint ""
		(layer "B.Cu")
		(at 54.665118 -346.788994 90)
		(property "Reference" "PC448_1"
			(at 0 0 90)
			(layer "B.SilkS")
			(hide yes)
			(effects
				(font
					(size 1.27 1.27)
				)
				(justify mirror)
			)
		)
		(property "Value" ""
			(at 0 0 90)
			(layer "B.Fab")
			(effects
				(font
					(size 1.27 1.27)
				)
				(justify mirror)
			)
		)
		(duplicate_pad_numbers_are_jumpers no)
		(fp_line
			(start 1.524 -0.762)
			(end -1.524 -0.762)
			(stroke
				(width 0.1524)
				(type default)
			)
			(layer "B.SilkS")
		)
		(fp_line
			(start -1.524 -0.762)
			(end -1.524 0.762)
			(stroke
				(width 0.1524)
				(type default)
			)
			(layer "B.SilkS")
		)
		(fp_line
			(start 1.524 0.762)
			(end 1.524 -0.762)
			(stroke
				(width 0.1524)
				(type default)
			)
			(layer "B.SilkS")
		)
		(fp_line
			(start -1.524 0.762)
			(end 1.524 0.762)
			(stroke
				(width 0.1524)
				(type default)
			)
			(layer "B.SilkS")
		)
		(fp_line
			(start 1.1049 -0.724916)
			(end 1.1049 0.724916)
			(stroke
				(width 0.1)
				(type default)
			)
			(layer "B.Fab")
		)
		(fp_line
			(start -1.1049 -0.724916)
			(end 1.1049 -0.724916)
			(stroke
				(width 0.1)
				(type default)
			)
			(layer "B.Fab")
		)
		(fp_line
			(start 1.1049 0.724916)
			(end -1.1049 0.724916)
			(stroke
				(width 0.1)
				(type default)
			)
			(layer "B.Fab")
		)
		(fp_line
			(start -1.1049 0.724916)
			(end -1.1049 -0.724916)
			(stroke
				(width 0.1)
				(type default)
			)
			(layer "B.Fab")
		)
		(pad "1" smd rect
			(at 0.889 0 90)
			(size 1.016 1.27)
			(layers "B.Cu" "B.Mask" "B.Paste")
			(net "SW_P12V_AUX_PVDDIO_P1_FLT")
		)
		(pad "2" smd rect
			(at -0.889 0 90)
			(size 1.016 1.27)
			(layers "B.Cu" "B.Mask" "B.Paste")
			(net "GND")
		)
	)
	(footprint ""
		(layer "B.Cu")
		(at 428.98695 -40.071548 180)
		(property "Reference" "R1262"
			(at 0 0 0)
			(layer "B.SilkS")
			(hide yes)
			(effects
				(font
					(size 1.27 1.27)
				)
				(justify mirror)
			)
		)
		(property "Value" ""
			(at 0 0 0)
			(layer "B.Fab")
			(effects
				(font
					(size 1.27 1.27)
				)
				(justify mirror)
			)
		)
		(duplicate_pad_numbers_are_jumpers no)
		(fp_line
			(start 0.7874 0.4064)
			(end 0.7874 -0.4064)
			(stroke
				(width 0.1524)
				(type default)
			)
			(layer "B.SilkS")
		)
		(fp_line
			(start 0.7874 -0.4064)
			(end -0.7874 -0.4064)
			(stroke
				(width 0.1524)
				(type default)
			)
			(layer "B.SilkS")
		)
		(fp_line
			(start -0.7874 0.4064)
			(end 0.7874 0.4064)
			(stroke
				(width 0.1524)
				(type default)
			)
			(layer "B.SilkS")
		)
		(fp_line
			(start -0.7874 -0.4064)
			(end -0.7874 0.4064)
			(stroke
				(width 0.1524)
				(type default)
			)
			(layer "B.SilkS")
		)
		(fp_line
			(start 0.67945 0.3048)
			(end 0.67945 -0.305054)
			(stroke
				(width 0.1)
				(type default)
			)
			(layer "B.Fab")
		)
		(fp_line
			(start 0.67945 -0.305054)
			(end 0.12065 -0.305054)
			(stroke
				(width 0.1)
				(type default)
			)
			(layer "B.Fab")
		)
		(fp_line
			(start 0.12065 0.3048)
			(end 0.67945 0.3048)
			(stroke
				(width 0.1)
				(type default)
			)
			(layer "B.Fab")
		)
		(fp_line
			(start 0.12065 0.2794)
			(end 0.12065 0.3048)
			(stroke
				(width 0.1)
				(type default)
			)
			(layer "B.Fab")
		)
		(fp_line
			(start 0.12065 -0.2794)
			(end -0.12065 -0.2794)
			(stroke
				(width 0.1)
				(type default)
			)
			(layer "B.Fab")
		)
		(fp_line
			(start 0.12065 -0.305054)
			(end 0.12065 -0.2794)
			(stroke
				(width 0.1)
				(type default)
			)
			(layer "B.Fab")
		)
		(fp_line
			(start -0.120396 0.3048)
			(end -0.120396 0.2794)
			(stroke
				(width 0.1)
				(type default)
			)
			(layer "B.Fab")
		)
		(fp_line
			(start -0.120396 0.2794)
			(end 0.12065 0.2794)
			(stroke
				(width 0.1)
				(type default)
			)
			(layer "B.Fab")
		)
		(fp_line
			(start -0.12065 -0.2794)
			(end -0.12065 -0.3048)
			(stroke
				(width 0.1)
				(type default)
			)
			(layer "B.Fab")
		)
		(fp_line
			(start -0.12065 -0.3048)
			(end -0.67945 -0.3048)
			(stroke
				(width 0.1)
				(type default)
			)
			(layer "B.Fab")
		)
		(fp_line
			(start -0.67945 0.3048)
			(end -0.120396 0.3048)
			(stroke
				(width 0.1)
				(type default)
			)
			(layer "B.Fab")
		)
		(fp_line
			(start -0.67945 -0.3048)
			(end -0.67945 0.3048)
			(stroke
				(width 0.1)
				(type default)
			)
			(layer "B.Fab")
		)
		(pad "1" smd circle
			(at 0.40005 0)
			(size 0 0)
			(layers "B.Cu" "B.Mask" "B.Paste")
			(net "P1V8_AUX")
		)
		(pad "2" smd circle
			(at -0.40005 0)
			(size 0 0)
			(layers "B.Cu" "B.Mask" "B.Paste")
			(net "BMC_JTAG_SEL")
		)
	)
	(footprint ""
		(layer "B.Cu")
		(at 302.133 -356.997 180)
		(property "Reference" "R8048"
			(at 0 0 0)
			(layer "B.SilkS")
			(hide yes)
			(effects
				(font
					(size 1.27 1.27)
				)
				(justify mirror)
			)
		)
		(property "Value" ""
			(at 0 0 0)
			(layer "B.Fab")
			(effects
				(font
					(size 1.27 1.27)
				)
				(justify mirror)
			)
		)
		(duplicate_pad_numbers_are_jumpers no)
		(fp_line
			(start 0.7874 0.4064)
			(end 0.7874 -0.4064)
			(stroke
				(width 0.1524)
				(type default)
			)
			(layer "B.SilkS")
		)
		(fp_line
			(start 0.7874 -0.4064)
			(end -0.7874 -0.4064)
			(stroke
				(width 0.1524)
				(type default)
			)
			(layer "B.SilkS")
		)
		(fp_line
			(start -0.7874 0.4064)
			(end 0.7874 0.4064)
			(stroke
				(width 0.1524)
				(type default)
			)
			(layer "B.SilkS")
		)
		(fp_line
			(start -0.7874 -0.4064)
			(end -0.7874 0.4064)
			(stroke
				(width 0.1524)
				(type default)
			)
			(layer "B.SilkS")
		)
		(fp_line
			(start 0.67945 0.3048)
			(end 0.67945 -0.305054)
			(stroke
				(width 0.1)
				(type default)
			)
			(layer "B.Fab")
		)
		(fp_line
			(start 0.67945 -0.305054)
			(end 0.12065 -0.305054)
			(stroke
				(width 0.1)
				(type default)
			)
			(layer "B.Fab")
		)
		(fp_line
			(start 0.12065 0.3048)
			(end 0.67945 0.3048)
			(stroke
				(width 0.1)
				(type default)
			)
			(layer "B.Fab")
		)
		(fp_line
			(start 0.12065 0.2794)
			(end 0.12065 0.3048)
			(stroke
				(width 0.1)
				(type default)
			)
			(layer "B.Fab")
		)
		(fp_line
			(start 0.12065 -0.2794)
			(end -0.12065 -0.2794)
			(stroke
				(width 0.1)
				(type default)
			)
			(layer "B.Fab")
		)
		(fp_line
			(start 0.12065 -0.305054)
			(end 0.12065 -0.2794)
			(stroke
				(width 0.1)
				(type default)
			)
			(layer "B.Fab")
		)
		(fp_line
			(start -0.120396 0.3048)
			(end -0.120396 0.2794)
			(stroke
				(width 0.1)
				(type default)
			)
			(layer "B.Fab")
		)
		(fp_line
			(start -0.120396 0.2794)
			(end 0.12065 0.2794)
			(stroke
				(width 0.1)
				(type default)
			)
			(layer "B.Fab")
		)
		(fp_line
			(start -0.12065 -0.2794)
			(end -0.12065 -0.3048)
			(stroke
				(width 0.1)
				(type default)
			)
			(layer "B.Fab")
		)
		(fp_line
			(start -0.12065 -0.3048)
			(end -0.67945 -0.3048)
			(stroke
				(width 0.1)
				(type default)
			)
			(layer "B.Fab")
		)
		(fp_line
			(start -0.67945 0.3048)
			(end -0.120396 0.3048)
			(stroke
				(width 0.1)
				(type default)
			)
			(layer "B.Fab")
		)
		(fp_line
			(start -0.67945 -0.3048)
			(end -0.67945 0.3048)
			(stroke
				(width 0.1)
				(type default)
			)
			(layer "B.Fab")
		)
		(pad "1" smd circle
			(at 0.40005 0)
			(size 0 0)
			(layers "B.Cu" "B.Mask" "B.Paste")
			(net "PVDD18_S5_P0")
		)
		(pad "2" smd circle
			(at -0.40005 0)
			(size 0 0)
			(layers "B.Cu" "B.Mask" "B.Paste")
			(net "SVID_PVDDCR_CPU1_P0_SVC_R")
		)
	)
)
